# BASEBOARD_FAB2 (Tioga Pass) — schematic netlist excerpt (pin names and nets, part order shuffled) for the footprints in the layout excerpt that follows; sources: Cadence DE-HDL packaged netlist, KiCad conversion of Wiwynn_Tioga_Pass_MB.brd

J4G2  SCONN288_H44441004  SCONN  pkg PIP  page 45
  \12v\(1)  = P12V_NVDIMM_ABC
  VSS(93)  = GND
  DQ(4)  = M_B_DQ<5>
  VSS(92)  = GND
  DQ(0)  = M_B_DQ<1>
  VSS(91)  = GND
  DQS9P  = M_B_DQS_DP<9>
  DQS9N  = M_B_DQS_DN<9>
  VSS(90)  = GND
  DQ(6)  = M_B_DQ<7>
  VSS(89)  = GND
  DQ(2)  = M_B_DQ<3>
  VSS(88)  = GND
  DQ(12)  = M_B_DQ<13>
  VSS(87)  = GND
  DQ(8)  = M_B_DQ<9>
  VSS(86)  = GND
  DQS10P  = M_B_DQS_DP<10>
  DQS10N  = M_B_DQS_DN<10>
  VSS(85)  = GND
  DQ(14)  = M_B_DQ<15>
  VSS(84)  = GND
  DQ(10)  = M_B_DQ<11>
  VSS(83)  = GND
  DQ(20)  = M_B_DQ<21>
  VSS(82)  = GND
  DQ(16)  = M_B_DQ<17>
  VSS(81)  = GND
  DQS11P  = M_B_DQS_DP<11>
  DQS11N  = M_B_DQS_DN<11>
  VSS(80)  = GND
  DQ(22)  = M_B_DQ<23>
  VSS(79)  = GND
  DQ(18)  = M_B_DQ<19>
  VSS(78)  = GND
  DQ(28)  = M_B_DQ<29>
  VSS(77)  = GND
  DQ(24)  = M_B_DQ<25>
  VSS(76)  = GND
  DQS12P  = M_B_DQS_DP<12>
  DQS12N  = M_B_DQS_DN<12>
  VSS(75)  = GND
  DQ(30)  = M_B_DQ<31>
  VSS(74)  = GND
  DQ(26)  = M_B_DQ<27>
  VSS(73)  = GND
  CB(4)  = M_B_ECC<5>
  VSS(72)  = GND
  CB(0)  = M_B_ECC<1>
  VSS(71)  = GND
  DQS17P  = M_B_DQS_DP<17>
  DQS17N  = M_B_DQS_DN<17>
  VSS(70)  = GND
  CB(6)  = M_B_ECC<7>
  VSS(69)  = GND
  CB(2)  = M_B_ECC<3>
  VSS(68)  = GND
  RESET_N  = M_ABC_RST_N
  VDD(25)  = PVDDQ_ABC
  CKE(0)  = M_B_CKE<0>
  VDD(24)  = PVDDQ_ABC
  ACT_N  = M_B_ACT_N
  BG(0)  = M_B_BG<0>
  VDD(23)  = PVDDQ_ABC
  A12  = M_B_MA<12>
  A9  = M_B_MA<9>
  VDD(22)  = PVDDQ_ABC
  A8  = M_B_MA<8>
  A6  = M_B_MA<6>
  VDD(21)  = PVDDQ_ABC
  A3  = M_B_MA<3>
  A1  = M_B_MA<1>
  VDD(20)  = PVDDQ_ABC
  CK0P  = M_B_CLK_DP<0>
  CK0N  = M_B_CLK_DN<0>
  VDD(19)  = PVDDQ_ABC
  VTT(1)  = PVTT_ABC
  EVENT_N  = FM_DIMM_EVENT_COD_N
  A0  = M_B_MA<0>
  VDD(18)  = PVDDQ_ABC
  BA(0)  = M_B_BA<0>
  A16_RAS_N  = M_B_MA<16>
  VDD(17)  = PVDDQ_ABC
  S0_N  = M_B_CS_N<0>
  VDD(16)  = PVDDQ_ABC
  A15_CAS_N  = M_B_MA<15>
  ODT(0)  = M_B_ODT<0>
  VDD(15)  = PVDDQ_ABC
  S1_N  = M_B_CS_N<1>
  VDD(14)  = PVDDQ_ABC
  ODT(1)  = M_B_ODT<1>
  VDD(13)  = PVDDQ_ABC
  S2_N_C(0)  = M_B_CS_N<2>
  VSS(67)  = GND
  DQ(36)  = M_B_DQ<37>
  VSS(66)  = GND
  DQ(32)  = M_B_DQ<33>
  VSS(65)  = GND
  DQS13P  = M_B_DQS_DP<13>
  DQS13N  = M_B_DQS_DN<13>
  VSS(64)  = GND
  DQ(38)  = M_B_DQ<39>
  VSS(63)  = GND
  DQ(34)  = M_B_DQ<35>
  VSS(62)  = GND
  DQ(44)  = M_B_DQ<45>
  VSS(61)  = GND
  DQ(40)  = M_B_DQ<41>
  VSS(60)  = GND
  DQS14P  = M_B_DQS_DP<14>
  DQS14N  = M_B_DQS_DN<14>
  VSS(59)  = GND
  DQ(46)  = M_B_DQ<47>
  VSS(58)  = GND
  DQ(42)  = M_B_DQ<43>
  VSS(57)  = GND
  DQ(52)  = M_B_DQ<53>
  VSS(56)  = GND
  DQ(48)  = M_B_DQ<49>
  VSS(55)  = GND
  DQS15P  = M_B_DQS_DP<15>
  DQS15N  = M_B_DQS_DN<15>
  VSS(54)  = GND
  DQ(54)  = M_B_DQ<55>
  VSS(53)  = GND
  DQ(50)  = M_B_DQ<51>
  VSS(52)  = GND
  DQ(60)  = M_B_DQ<61>
  VSS(51)  = GND
  DQ(56)  = M_B_DQ<57>
  VSS(50)  = GND
  DQS16P  = M_B_DQS_DP<16>
  DQS16N  = M_B_DQS_DN<16>
  VSS(49)  = GND
  DQ(62)  = M_B_DQ<63>
  VSS(48)  = GND
  DQ(58)  = M_B_DQ<59>
  VSS(47)  = GND
  SA(0)  = GND
  SA(1)  = PVPP_ABC
  SCL  = SMB_DDR_ABC_VPP_SCL
  VPP(4)  = PVPP_ABC
  VPP(3)  = PVPP_ABC
  RFU(2)  = TP_CH_B_DIMM_B0_RFU_2
  \12v\(0)  = P12V_NVDIMM_ABC
  VREFCA  = M_B_VREF
  VSS(46)  = GND
  DQ(5)  = M_B_DQ<4>
  VSS(45)  = GND
  DQ(1)  = M_B_DQ<0>
  VSS(44)  = GND
  DQS0N  = M_B_DQS_DN<0>
  DQS0P  = M_B_DQS_DP<0>
  VSS(43)  = GND
  DQ(7)  = M_B_DQ<6>
  VSS(42)  = GND
  DQ(3)  = M_B_DQ<2>
  VSS(41)  = GND
  DQ(13)  = M_B_DQ<12>
  VSS(40)  = GND
  DQ(9)  = M_B_DQ<8>
  VSS(39)  = GND
  DQS1N  = M_B_DQS_DN<1>
  DQS1P  = M_B_DQS_DP<1>
  VSS(38)  = GND
  DQ(15)  = M_B_DQ<14>
  VSS(37)  = GND
  DQ(11)  = M_B_DQ<10>
  VSS(36)  = GND
  DQ(21)  = M_B_DQ<20>
  VSS(35)  = GND
  DQ(17)  = M_B_DQ<16>
  VSS(34)  = GND
  DQS2N  = M_B_DQS_DN<2>
  DQS2P  = M_B_DQS_DP<2>
  VSS(33)  = GND
  DQ(23)  = M_B_DQ<22>
  VSS(32)  = GND
  DQ(19)  = M_B_DQ<18>
  VSS(31)  = GND
  DQ(29)  = M_B_DQ<28>
  VSS(30)  = GND
  DQ(25)  = M_B_DQ<24>
  VSS(29)  = GND
  DQS3N  = M_B_DQS_DN<3>
  DQS3P  = M_B_DQS_DP<3>
  VSS(28)  = GND
  DQ(31)  = M_B_DQ<30>
  VSS(27)  = GND
  DQ(27)  = M_B_DQ<26>
  VSS(26)  = GND
  CB(5)  = M_B_ECC<4>
  VSS(25)  = GND
  CB(1)  = M_B_ECC<0>
  VSS(24)  = GND
  DQS8N  = M_B_DQS_DN<8>
  DQS8P  = M_B_DQS_DP<8>
  VSS(23)  = GND
  CB(7)  = M_B_ECC<6>
  VSS(22)  = GND
  CB(3)  = M_B_ECC<2>
  VSS(21)  = GND
  CKE(1)  = M_B_CKE<1>
  VDD(12)  = PVDDQ_ABC
  RFU(0)  = TP_CH_B_DIMM_B0_RFU_0
  VDD(11)  = PVDDQ_ABC
  BG(1)  = M_B_BG<1>
  ALERT_N  = M_B_ALERT_N
  VDD(10)  = PVDDQ_ABC
  A11  = M_B_MA<11>
  A7  = M_B_MA<7>
  VDD(9)  = PVDDQ_ABC
  A5  = M_B_MA<5>
  A4  = M_B_MA<4>
  VDD(8)  = PVDDQ_ABC
  A2  = M_B_MA<2>
  VDD(7)  = PVDDQ_ABC
  CK1P  = M_B_CLK_DP<1>
  CK1N  = M_B_CLK_DN<1>
  VDD(6)  = PVDDQ_ABC
  VTT(0)  = PVTT_ABC
  PAR  = M_B_PAR
  VDD(5)  = PVDDQ_ABC
  BA(1)  = M_B_BA<1>
  A10  = M_B_MA<10>
  VDD(4)  = PVDDQ_ABC
  RFU(1)  = TP_CH_B_DIMM_B0_RFU_1
  A14_WE_N  = M_B_MA<14>
  VDD(3)  = PVDDQ_ABC
  SAVE_N_NC  = FM_ADR_COMPLETE_ABC_N
  VDD(2)  = PVDDQ_ABC
  A13  = M_B_MA<13>
  VDD(1)  = PVDDQ_ABC
  A17  = M_B_MA<17>
  C(2)  = M_B_C<2>
  VDD(0)  = PVDDQ_ABC
  S3_N_C(1)  = M_B_CS_N<3>
  SA(2)  = GND
  VSS(20)  = GND
  DQ(37)  = M_B_DQ<36>
  VSS(19)  = GND
  DQ(33)  = M_B_DQ<32>
  VSS(18)  = GND
  DQS4N  = M_B_DQS_DN<4>
  DQS4P  = M_B_DQS_DP<4>
  VSS(17)  = GND
  DQ(39)  = M_B_DQ<38>
  VSS(16)  = GND
  DQ(35)  = M_B_DQ<34>
  VSS(15)  = GND
  DQ(45)  = M_B_DQ<44>
  VSS(14)  = GND
  DQ(41)  = M_B_DQ<40>
  VSS(13)  = GND
  DQS5N  = M_B_DQS_DN<5>
  DQS5P  = M_B_DQS_DP<5>
  VSS(12)  = GND
  DQ(47)  = M_B_DQ<46>
  VSS(11)  = GND
  DQ(43)  = M_B_DQ<42>
  VSS(10)  = GND
  DQ(53)  = M_B_DQ<52>
  VSS(9)  = GND
  DQ(49)  = M_B_DQ<48>
  VSS(8)  = GND
  DQS6N  = M_B_DQS_DN<6>
  DQS6P  = M_B_DQS_DP<6>
  VSS(7)  = GND
  DQ(55)  = M_B_DQ<54>
  VSS(6)  = GND
  DQ(51)  = M_B_DQ<50>
  VSS(5)  = GND
  DQ(61)  = M_B_DQ<60>
  VSS(4)  = GND
  DQ(57)  = M_B_DQ<56>
  VSS(3)  = GND
  DQS7N  = M_B_DQS_DN<7>
  DQS7P  = M_B_DQS_DP<7>
  VSS(2)  = GND
  DQ(63)  = M_B_DQ<62>
  VSS(1)  = GND
  DQ(59)  = M_B_DQ<58>
  VSS(0)  = GND
  VDDSPD  = PVPP_ABC
  SDA  = SMB_DDR_ABC_VPP_SDA
  VPP(1)  = PVPP_ABC
  VPP(0)  = PVPP_ABC
  VPP(2)  = PVPP_ABC

(kicad_pcb
	(version 20260206)
	(generator "pcbnew")
	(generator_version "10.0")
	(general
		(thickness 1.6)
		(legacy_teardrops no)
	)
	(paper "A4")
	(title_block
		(title "Wiwynn_Tioga_Pass_MB.brd")
		(comment 1 "Tioga Pass / footprint 1899 of 4770 (J4G2), pads 102-152 of 291")
	)
	(layers
		(0 "F.Cu" signal "TOP")
		(4 "In1.Cu" signal "L2GND")
		(6 "In2.Cu" signal "L3")
		(8 "In3.Cu" signal "L4GND")
		(10 "In4.Cu" signal "L5")
		(12 "In5.Cu" signal "L6GND")
		(14 "In6.Cu" signal "L7VCC")
		(16 "In7.Cu" signal "L8VCC")
		(18 "In8.Cu" signal "L9GND")
		(20 "In9.Cu" signal "L10")
		(22 "In10.Cu" signal "L11GND")
		(24 "In11.Cu" signal "L12")
		(26 "In12.Cu" signal "L13GND")
		(2 "B.Cu" signal "BOTTOM")
		(9 "F.Adhes" user "F.Adhesive")
		(11 "B.Adhes" user "B.Adhesive")
		(13 "F.Paste" user "Package Geometry/Pastemask Top")
		(15 "B.Paste" user "Package Geometry/Pastemask Bottom")
		(5 "F.SilkS" user "Ref Des/Silkscreen Top")
		(7 "B.SilkS" user "Ref Des/Silkscreen Bottom")
		(1 "F.Mask" user "Board Geometry/Soldermask Top")
		(3 "B.Mask" user "Board Geometry/Soldermask Bottom")
		(17 "Dwgs.User" user "User.Drawings")
		(19 "Cmts.User" user "User.Comments")
		(21 "Eco1.User" user "User.Eco1")
		(23 "Eco2.User" user "User.Eco2")
		(25 "Edge.Cuts" user "Board Geometry/Outline")
		(27 "Margin" user)
		(31 "F.CrtYd" user "Package Geometry/Place Bound Top")
		(29 "B.CrtYd" user "Package Geometry/Place Bound Bottom")
		(35 "F.Fab" user "Ref Des/Assembly Top")
		(33 "B.Fab" user "Ref Des/Assembly Bottom")
	)
	(footprint ""
		(layer "F.Cu")
		(at 194.700398 -5.822442 90)
		(property "Reference" "J4G2"
			(at 6.596888 37.58311 0)
			(unlocked yes)
			(layer "F.SilkS")
			(effects
				(font
					(size 0.7874 0.5842)
					(thickness 0.1524)
				)
				(justify left)
			)
		)
		(property "Value" ""
			(at 0 0 90)
			(layer "F.Fab")
			(effects
				(font
					(size 1.27 1.27)
				)
			)
		)
		(duplicate_pad_numbers_are_jumpers no)
		(pad "99" smd rect
			(at 0 88.399874 90)
			(size 1.8034 0.508)
			(layers "F.Cu" "F.Mask" "F.Paste")
			(net "M_B_DQS_DP<13>")
		)
		(pad "100" smd rect
			(at 0 89.250012 90)
			(size 1.8034 0.508)
			(layers "F.Cu" "F.Mask" "F.Paste")
			(net "M_B_DQS_DN<13>")
		)
		(pad "101" smd rect
			(at 0 90.099896 90)
			(size 1.8034 0.508)
			(layers "F.Cu" "F.Mask" "F.Paste")
			(net "GND")
		)
		(pad "102" smd rect
			(at 0 90.950034 90)
			(size 1.8034 0.508)
			(layers "F.Cu" "F.Mask" "F.Paste")
			(net "M_B_DQ<39>")
		)
		(pad "103" smd rect
			(at 0 91.799918 90)
			(size 1.8034 0.508)
			(layers "F.Cu" "F.Mask" "F.Paste")
			(net "GND")
		)
		(pad "104" smd rect
			(at 0 92.650056 90)
			(size 1.8034 0.508)
			(layers "F.Cu" "F.Mask" "F.Paste")
			(net "M_B_DQ<35>")
		)
		(pad "105" smd rect
			(at 0 93.49994 90)
			(size 1.8034 0.508)
			(layers "F.Cu" "F.Mask" "F.Paste")
			(net "GND")
		)
		(pad "106" smd rect
			(at 0 94.350078 90)
			(size 1.8034 0.508)
			(layers "F.Cu" "F.Mask" "F.Paste")
			(net "M_B_DQ<45>")
		)
		(pad "107" smd rect
			(at 0 95.199962 90)
			(size 1.8034 0.508)
			(layers "F.Cu" "F.Mask" "F.Paste")
			(net "GND")
		)
		(pad "108" smd rect
			(at 0 96.0501 90)
			(size 1.8034 0.508)
			(layers "F.Cu" "F.Mask" "F.Paste")
			(net "M_B_DQ<41>")
		)
		(pad "109" smd rect
			(at 0 96.899984 90)
			(size 1.8034 0.508)
			(layers "F.Cu" "F.Mask" "F.Paste")
			(net "GND")
		)
		(pad "110" smd rect
			(at 0 97.750122 90)
			(size 1.8034 0.508)
			(layers "F.Cu" "F.Mask" "F.Paste")
			(net "M_B_DQS_DP<14>")
		)
		(pad "111" smd rect
			(at 0 98.600006 90)
			(size 1.8034 0.508)
			(layers "F.Cu" "F.Mask" "F.Paste")
			(net "M_B_DQS_DN<14>")
		)
		(pad "112" smd rect
			(at 0 99.44989 90)
			(size 1.8034 0.508)
			(layers "F.Cu" "F.Mask" "F.Paste")
			(net "GND")
		)
		(pad "113" smd rect
			(at 0 100.300028 90)
			(size 1.8034 0.508)
			(layers "F.Cu" "F.Mask" "F.Paste")
			(net "M_B_DQ<47>")
		)
		(pad "114" smd rect
			(at 0 101.149912 90)
			(size 1.8034 0.508)
			(layers "F.Cu" "F.Mask" "F.Paste")
			(net "GND")
		)
		(pad "115" smd rect
			(at 0 102.00005 90)
			(size 1.8034 0.508)
			(layers "F.Cu" "F.Mask" "F.Paste")
			(net "M_B_DQ<43>")
		)
		(pad "116" smd rect
			(at 0 102.849934 90)
			(size 1.8034 0.508)
			(layers "F.Cu" "F.Mask" "F.Paste")
			(net "GND")
		)
		(pad "117" smd rect
			(at 0 103.700072 90)
			(size 1.8034 0.508)
			(layers "F.Cu" "F.Mask" "F.Paste")
			(net "M_B_DQ<53>")
		)
		(pad "118" smd rect
			(at 0 104.549956 90)
			(size 1.8034 0.508)
			(layers "F.Cu" "F.Mask" "F.Paste")
			(net "GND")
		)
		(pad "119" smd rect
			(at 0 105.400094 90)
			(size 1.8034 0.508)
			(layers "F.Cu" "F.Mask" "F.Paste")
			(net "M_B_DQ<49>")
		)
		(pad "120" smd rect
			(at 0 106.249978 90)
			(size 1.8034 0.508)
			(layers "F.Cu" "F.Mask" "F.Paste")
			(net "GND")
		)
		(pad "121" smd rect
			(at 0 107.100116 90)
			(size 1.8034 0.508)
			(layers "F.Cu" "F.Mask" "F.Paste")
			(net "M_B_DQS_DP<15>")
		)
		(pad "122" smd rect
			(at 0 107.95 90)
			(size 1.8034 0.508)
			(layers "F.Cu" "F.Mask" "F.Paste")
			(net "M_B_DQS_DN<15>")
		)
		(pad "123" smd rect
			(at 0 108.799884 90)
			(size 1.8034 0.508)
			(layers "F.Cu" "F.Mask" "F.Paste")
			(net "GND")
		)
		(pad "124" smd rect
			(at 0 109.650022 90)
			(size 1.8034 0.508)
			(layers "F.Cu" "F.Mask" "F.Paste")
			(net "M_B_DQ<55>")
		)
		(pad "125" smd rect
			(at 0 110.499906 90)
			(size 1.8034 0.508)
			(layers "F.Cu" "F.Mask" "F.Paste")
			(net "GND")
		)
		(pad "126" smd rect
			(at 0 111.350044 90)
			(size 1.8034 0.508)
			(layers "F.Cu" "F.Mask" "F.Paste")
			(net "M_B_DQ<51>")
		)
		(pad "127" smd rect
			(at 0 112.199928 90)
			(size 1.8034 0.508)
			(layers "F.Cu" "F.Mask" "F.Paste")
			(net "GND")
		)
		(pad "128" smd rect
			(at 0 113.050066 90)
			(size 1.8034 0.508)
			(layers "F.Cu" "F.Mask" "F.Paste")
			(net "M_B_DQ<61>")
		)
		(pad "129" smd rect
			(at 0 113.89995 90)
			(size 1.8034 0.508)
			(layers "F.Cu" "F.Mask" "F.Paste")
			(net "GND")
		)
		(pad "130" smd rect
			(at 0 114.750088 90)
			(size 1.8034 0.508)
			(layers "F.Cu" "F.Mask" "F.Paste")
			(net "M_B_DQ<57>")
		)
		(pad "131" smd rect
			(at 0 115.599972 90)
			(size 1.8034 0.508)
			(layers "F.Cu" "F.Mask" "F.Paste")
			(net "GND")
		)
		(pad "132" smd rect
			(at 0 116.45011 90)
			(size 1.8034 0.508)
			(layers "F.Cu" "F.Mask" "F.Paste")
			(net "M_B_DQS_DP<16>")
		)
		(pad "133" smd rect
			(at 0 117.299994 90)
			(size 1.8034 0.508)
			(layers "F.Cu" "F.Mask" "F.Paste")
			(net "M_B_DQS_DN<16>")
		)
		(pad "134" smd rect
			(at 0 118.149878 90)
			(size 1.8034 0.508)
			(layers "F.Cu" "F.Mask" "F.Paste")
			(net "GND")
		)
		(pad "135" smd rect
			(at 0 119.000016 90)
			(size 1.8034 0.508)
			(layers "F.Cu" "F.Mask" "F.Paste")
			(net "M_B_DQ<63>")
		)
		(pad "136" smd rect
			(at 0 119.8499 90)
			(size 1.8034 0.508)
			(layers "F.Cu" "F.Mask" "F.Paste")
			(net "GND")
		)
		(pad "137" smd rect
			(at 0 120.700038 90)
			(size 1.8034 0.508)
			(layers "F.Cu" "F.Mask" "F.Paste")
			(net "M_B_DQ<59>")
		)
		(pad "138" smd rect
			(at 0 121.549922 90)
			(size 1.8034 0.508)
			(layers "F.Cu" "F.Mask" "F.Paste")
			(net "GND")
		)
		(pad "139" smd rect
			(at 0 122.40006 90)
			(size 1.8034 0.508)
			(layers "F.Cu" "F.Mask" "F.Paste")
			(net "GND")
		)
		(pad "140" smd rect
			(at 0 123.249944 90)
			(size 1.8034 0.508)
			(layers "F.Cu" "F.Mask" "F.Paste")
			(net "PVPP_ABC")
		)
		(pad "141" smd rect
			(at 0 124.100082 90)
			(size 1.8034 0.508)
			(layers "F.Cu" "F.Mask" "F.Paste")
			(net "SMB_DDR_ABC_VPP_SCL")
		)
		(pad "142" smd rect
			(at 0 124.949966 90)
			(size 1.8034 0.508)
			(layers "F.Cu" "F.Mask" "F.Paste")
			(net "PVPP_ABC")
		)
		(pad "143" smd rect
			(at 0 125.800104 90)
			(size 1.8034 0.508)
			(layers "F.Cu" "F.Mask" "F.Paste")
			(net "PVPP_ABC")
		)
		(pad "144" smd rect
			(at 0 126.649988 90)
			(size 1.8034 0.508)
			(layers "F.Cu" "F.Mask" "F.Paste")
			(net "TP_CH_B_DIMM_B0_RFU_2")
		)
		(pad "145" smd rect
			(at 4.59994 0 90)
			(size 1.8034 0.508)
			(layers "F.Cu" "F.Mask" "F.Paste")
			(net "P12V_NVDIMM_ABC")
		)
		(pad "146" smd rect
			(at 4.59994 0.849884 90)
			(size 1.8034 0.508)
			(layers "F.Cu" "F.Mask" "F.Paste")
			(net "M_B_VREF")
		)
		(pad "147" smd rect
			(at 4.59994 1.700022 90)
			(size 1.8034 0.508)
			(layers "F.Cu" "F.Mask" "F.Paste")
			(net "GND")
		)
		(pad "148" smd rect
			(at 4.59994 2.549906 90)
			(size 1.8034 0.508)
			(layers "F.Cu" "F.Mask" "F.Paste")
			(net "M_B_DQ<4>")
		)
		(pad "149" smd rect
			(at 4.59994 3.400044 90)
			(size 1.8034 0.508)
			(layers "F.Cu" "F.Mask" "F.Paste")
			(net "GND")
		)
	)
)
